# T6G (Grand Teton) — schematic netlist excerpt (pin names and nets, part order shuffled) for the footprints in the layout excerpt that follows; sources: Cadence DE-HDL packaged netlist, KiCad conversion of 04192023_DAF0TMB3IC0_F0TG_MB_C_brd_V02_OCP.brd

PC170_2  Q_CAP  22UF 4V 20% X6S  pkg C0805  page 205 : A = PVDDIO_P0 ; B = GND
PC192_3  Q_CAP  22UF 4V 20% X6S  pkg C0805  page 206 : A = PVDDIO_P0 ; B = GND
R8153  Q_RES  1K 1% EMPTY  pkg 0402LF  page 210 : A = SVID_PVDDCR_CPU0_P1_SVTO ; B = GND

(kicad_pcb
	(version 20260206)
	(generator "pcbnew")
	(generator_version "10.0")
	(general
		(thickness 1.6)
		(legacy_teardrops no)
	)
	(paper "A4")
	(title_block
		(title "04192023_DAF0TMB3IC0_F0TG_MB_C_brd_V02_OCP.brd")
		(comment 1 "Grand Teton / footprints 5659-5661 of 8354")
	)
	(layers
		(0 "F.Cu" signal "TOP")
		(4 "In1.Cu" signal "GND")
		(6 "In2.Cu" signal "IN1")
		(8 "In3.Cu" signal "GND1")
		(10 "In4.Cu" signal "IN2")
		(12 "In5.Cu" signal "GND2")
		(14 "In6.Cu" signal "IN3")
		(16 "In7.Cu" signal "GND3")
		(18 "In8.Cu" signal "VCC")
		(20 "In9.Cu" signal "VCC1")
		(22 "In10.Cu" signal "GND4")
		(24 "In11.Cu" signal "IN4")
		(26 "In12.Cu" signal "GND5")
		(28 "In13.Cu" signal "IN5")
		(30 "In14.Cu" signal "GND6")
		(32 "In15.Cu" signal "IN6")
		(34 "In16.Cu" signal "GND7")
		(2 "B.Cu" signal "BOTTOM")
		(9 "F.Adhes" user "F.Adhesive")
		(11 "B.Adhes" user "B.Adhesive")
		(13 "F.Paste" user "Package Geometry/Pastemask Top")
		(15 "B.Paste" user "Package Geometry/Pastemask Bottom")
		(5 "F.SilkS" user "Ref Des/Silkscreen Top")
		(7 "B.SilkS" user "Ref Des/Silkscreen Bottom")
		(1 "F.Mask" user "Board Geometry/Soldermask Top")
		(3 "B.Mask" user "Board Geometry/Soldermask Bottom")
		(17 "Dwgs.User" user "User.Drawings")
		(19 "Cmts.User" user "User.Comments")
		(21 "Eco1.User" user "User.Eco1")
		(23 "Eco2.User" user "User.Eco2")
		(25 "Edge.Cuts" user "Board Geometry/Outline")
		(27 "Margin" user)
		(31 "F.CrtYd" user "Package Geometry/Place Bound Top")
		(29 "B.CrtYd" user "Package Geometry/Place Bound Bottom")
		(35 "F.Fab" user "Ref Des/Assembly Top")
		(33 "B.Fab" user "Ref Des/Assembly Bottom")
	)
	(footprint ""
		(layer "B.Cu")
		(at 88.177878 -148.94941)
		(property "Reference" "R8153"
			(at 0 0 0)
			(layer "B.SilkS")
			(hide yes)
			(effects
				(font
					(size 1.27 1.27)
				)
				(justify mirror)
			)
		)
		(property "Value" ""
			(at 0 0 0)
			(layer "B.Fab")
			(effects
				(font
					(size 1.27 1.27)
				)
				(justify mirror)
			)
		)
		(duplicate_pad_numbers_are_jumpers no)
		(fp_line
			(start -0.7874 -0.4064)
			(end -0.7874 0.4064)
			(stroke
				(width 0.1524)
				(type default)
			)
			(layer "B.SilkS")
		)
		(fp_line
			(start -0.7874 0.4064)
			(end 0.7874 0.4064)
			(stroke
				(width 0.1524)
				(type default)
			)
			(layer "B.SilkS")
		)
		(fp_line
			(start 0.7874 -0.4064)
			(end -0.7874 -0.4064)
			(stroke
				(width 0.1524)
				(type default)
			)
			(layer "B.SilkS")
		)
		(fp_line
			(start 0.7874 0.4064)
			(end 0.7874 -0.4064)
			(stroke
				(width 0.1524)
				(type default)
			)
			(layer "B.SilkS")
		)
		(fp_line
			(start -0.67945 -0.3048)
			(end -0.67945 0.3048)
			(stroke
				(width 0.1)
				(type default)
			)
			(layer "B.Fab")
		)
		(fp_line
			(start -0.67945 0.3048)
			(end -0.120396 0.3048)
			(stroke
				(width 0.1)
				(type default)
			)
			(layer "B.Fab")
		)
		(fp_line
			(start -0.12065 -0.3048)
			(end -0.67945 -0.3048)
			(stroke
				(width 0.1)
				(type default)
			)
			(layer "B.Fab")
		)
		(fp_line
			(start -0.12065 -0.2794)
			(end -0.12065 -0.3048)
			(stroke
				(width 0.1)
				(type default)
			)
			(layer "B.Fab")
		)
		(fp_line
			(start -0.120396 0.2794)
			(end 0.12065 0.2794)
			(stroke
				(width 0.1)
				(type default)
			)
			(layer "B.Fab")
		)
		(fp_line
			(start -0.120396 0.3048)
			(end -0.120396 0.2794)
			(stroke
				(width 0.1)
				(type default)
			)
			(layer "B.Fab")
		)
		(fp_line
			(start 0.12065 -0.305054)
			(end 0.12065 -0.2794)
			(stroke
				(width 0.1)
				(type default)
			)
			(layer "B.Fab")
		)
		(fp_line
			(start 0.12065 -0.2794)
			(end -0.12065 -0.2794)
			(stroke
				(width 0.1)
				(type default)
			)
			(layer "B.Fab")
		)
		(fp_line
			(start 0.12065 0.2794)
			(end 0.12065 0.3048)
			(stroke
				(width 0.1)
				(type default)
			)
			(layer "B.Fab")
		)
		(fp_line
			(start 0.12065 0.3048)
			(end 0.67945 0.3048)
			(stroke
				(width 0.1)
				(type default)
			)
			(layer "B.Fab")
		)
		(fp_line
			(start 0.67945 -0.305054)
			(end 0.12065 -0.305054)
			(stroke
				(width 0.1)
				(type default)
			)
			(layer "B.Fab")
		)
		(fp_line
			(start 0.67945 0.3048)
			(end 0.67945 -0.305054)
			(stroke
				(width 0.1)
				(type default)
			)
			(layer "B.Fab")
		)
		(pad "1" smd circle
			(at 0.40005 0 180)
			(size 0 0)
			(layers "B.Cu" "B.Mask" "B.Paste")
			(net "SVID_PVDDCR_CPU0_P1_SVTO")
		)
		(pad "2" smd circle
			(at -0.40005 0 180)
			(size 0 0)
			(layers "B.Cu" "B.Mask" "B.Paste")
			(net "GND")
		)
	)
	(footprint ""
		(layer "B.Cu")
		(at 280.855928 -338.005928 -90)
		(property "Reference" "PC192_3"
			(at 0 0 90)
			(layer "B.SilkS")
			(hide yes)
			(effects
				(font
					(size 1.27 1.27)
				)
				(justify mirror)
			)
		)
		(property "Value" ""
			(at 0 0 90)
			(layer "B.Fab")
			(effects
				(font
					(size 1.27 1.27)
				)
				(justify mirror)
			)
		)
		(duplicate_pad_numbers_are_jumpers no)
		(fp_line
			(start -1.524 0.762)
			(end 1.524 0.762)
			(stroke
				(width 0.1524)
				(type default)
			)
			(layer "B.SilkS")
		)
		(fp_line
			(start 1.524 0.762)
			(end 1.524 -0.762)
			(stroke
				(width 0.1524)
				(type default)
			)
			(layer "B.SilkS")
		)
		(fp_line
			(start -1.524 -0.762)
			(end -1.524 0.762)
			(stroke
				(width 0.1524)
				(type default)
			)
			(layer "B.SilkS")
		)
		(fp_line
			(start 1.524 -0.762)
			(end -1.524 -0.762)
			(stroke
				(width 0.1524)
				(type default)
			)
			(layer "B.SilkS")
		)
		(fp_line
			(start -1.1049 0.724916)
			(end -1.1049 -0.724916)
			(stroke
				(width 0.1)
				(type default)
			)
			(layer "B.Fab")
		)
		(fp_line
			(start 1.1049 0.724916)
			(end -1.1049 0.724916)
			(stroke
				(width 0.1)
				(type default)
			)
			(layer "B.Fab")
		)
		(fp_line
			(start -1.1049 -0.724916)
			(end 1.1049 -0.724916)
			(stroke
				(width 0.1)
				(type default)
			)
			(layer "B.Fab")
		)
		(fp_line
			(start 1.1049 -0.724916)
			(end 1.1049 0.724916)
			(stroke
				(width 0.1)
				(type default)
			)
			(layer "B.Fab")
		)
		(pad "1" smd rect
			(at 0.889 0 270)
			(size 1.016 1.27)
			(layers "B.Cu" "B.Mask" "B.Paste")
			(net "PVDDIO_P0")
		)
		(pad "2" smd rect
			(at -0.889 0 270)
			(size 1.016 1.27)
			(layers "B.Cu" "B.Mask" "B.Paste")
			(net "GND")
		)
	)
	(footprint ""
		(layer "B.Cu")
		(at 289.891216 -337.984846 -90)
		(property "Reference" "PC170_2"
			(at 0 0 90)
			(layer "B.SilkS")
			(hide yes)
			(effects
				(font
					(size 1.27 1.27)
				)
				(justify mirror)
			)
		)
		(property "Value" ""
			(at 0 0 90)
			(layer "B.Fab")
			(effects
				(font
					(size 1.27 1.27)
				)
				(justify mirror)
			)
		)
		(duplicate_pad_numbers_are_jumpers no)
		(fp_line
			(start -1.524 0.762)
			(end 1.524 0.762)
			(stroke
				(width 0.1524)
				(type default)
			)
			(layer "B.SilkS")
		)
		(fp_line
			(start 1.524 0.762)
			(end 1.524 -0.762)
			(stroke
				(width 0.1524)
				(type default)
			)
			(layer "B.SilkS")
		)
		(fp_line
			(start -1.524 -0.762)
			(end -1.524 0.762)
			(stroke
				(width 0.1524)
				(type default)
			)
			(layer "B.SilkS")
		)
		(fp_line
			(start 1.524 -0.762)
			(end -1.524 -0.762)
			(stroke
				(width 0.1524)
				(type default)
			)
			(layer "B.SilkS")
		)
		(fp_line
			(start -1.1049 0.724916)
			(end -1.1049 -0.724916)
			(stroke
				(width 0.1)
				(type default)
			)
			(layer "B.Fab")
		)
		(fp_line
			(start 1.1049 0.724916)
			(end -1.1049 0.724916)
			(stroke
				(width 0.1)
				(type default)
			)
			(layer "B.Fab")
		)
		(fp_line
			(start -1.1049 -0.724916)
			(end 1.1049 -0.724916)
			(stroke
				(width 0.1)
				(type default)
			)
			(layer "B.Fab")
		)
		(fp_line
			(start 1.1049 -0.724916)
			(end 1.1049 0.724916)
			(stroke
				(width 0.1)
				(type default)
			)
			(layer "B.Fab")
		)
		(pad "1" smd rect
			(at 0.889 0 270)
			(size 1.016 1.27)
			(layers "B.Cu" "B.Mask" "B.Paste")
			(net "PVDDIO_P0")
		)
		(pad "2" smd rect
			(at -0.889 0 270)
			(size 1.016 1.27)
			(layers "B.Cu" "B.Mask" "B.Paste")
			(net "GND")
		)
	)
)
